(kicad_pcb
	(version 20260206)
	(generator "pcbnew")
	(generator_version "10.0")
	(general
		(thickness 1.6)
		(legacy_teardrops no)
	)
	(paper "A4")
	(title_block
		(title "12092022_DA0F0TFB6D0_F0T_FAN_BOARD_MP5048_D_brd_v02_OCP.brd")
		(comment 1 "Grand Teton / footprints 50-55 of 924")
	)
	(layers
		(0 "F.Cu" signal "TOP")
		(4 "In1.Cu" signal "GND")
		(6 "In2.Cu" signal "IN1")
		(8 "In3.Cu" signal "IN2")
		(10 "In4.Cu" signal "GND1")
		(2 "B.Cu" signal "BOTTOM")
		(9 "F.Adhes" user "F.Adhesive")
		(11 "B.Adhes" user "B.Adhesive")
		(13 "F.Paste" user "Package Geometry/Pastemask Top")
		(15 "B.Paste" user "Package Geometry/Pastemask Bottom")
		(5 "F.SilkS" user "Ref Des/Silkscreen Top")
		(7 "B.SilkS" user "Ref Des/Silkscreen Bottom")
		(1 "F.Mask" user "Board Geometry/Soldermask Top")
		(3 "B.Mask" user "Board Geometry/Soldermask Bottom")
		(17 "Dwgs.User" user "User.Drawings")
		(19 "Cmts.User" user "User.Comments")
		(21 "Eco1.User" user "User.Eco1")
		(23 "Eco2.User" user "User.Eco2")
		(25 "Edge.Cuts" user "Board Geometry/Outline")
		(27 "Margin" user)
		(31 "F.CrtYd" user "Package Geometry/Place Bound Top")
		(29 "B.CrtYd" user "Package Geometry/Place Bound Bottom")
		(35 "F.Fab" user "Ref Des/Assembly Top")
		(33 "B.Fab" user "Ref Des/Assembly Bottom")
	)
	(footprint ""
		(layer "F.Cu")
		(at 37.211 -199.771)
		(property "Reference" "R5402"
			(at 0 0 0)
			(layer "F.SilkS")
			(hide yes)
			(effects
				(font
					(size 1.27 1.27)
				)
			)
		)
		(property "Value" ""
			(at 0 0 0)
			(layer "F.Fab")
			(effects
				(font
					(size 1.27 1.27)
				)
			)
		)
		(duplicate_pad_numbers_are_jumpers no)
		(fp_line
			(start -0.7874 -0.4064)
			(end 0.7874 -0.4064)
			(stroke
				(width 0.1524)
				(type default)
			)
			(layer "F.SilkS")
		)
		(fp_line
			(start -0.7874 0.4064)
			(end -0.7874 -0.4064)
			(stroke
				(width 0.1524)
				(type default)
			)
			(layer "F.SilkS")
		)
		(fp_line
			(start 0.7874 -0.4064)
			(end 0.7874 0.4064)
			(stroke
				(width 0.1524)
				(type default)
			)
			(layer "F.SilkS")
		)
		(fp_line
			(start 0.7874 0.4064)
			(end -0.7874 0.4064)
			(stroke
				(width 0.1524)
				(type default)
			)
			(layer "F.SilkS")
		)
		(fp_line
			(start -0.67945 -0.305054)
			(end -0.12065 -0.305054)
			(stroke
				(width 0.1)
				(type default)
			)
			(layer "F.Fab")
		)
		(fp_line
			(start -0.67945 0.3048)
			(end -0.67945 -0.305054)
			(stroke
				(width 0.1)
				(type default)
			)
			(layer "F.Fab")
		)
		(fp_line
			(start -0.12065 -0.305054)
			(end -0.12065 -0.2794)
			(stroke
				(width 0.1)
				(type default)
			)
			(layer "F.Fab")
		)
		(fp_line
			(start -0.12065 -0.2794)
			(end 0.12065 -0.2794)
			(stroke
				(width 0.1)
				(type default)
			)
			(layer "F.Fab")
		)
		(fp_line
			(start -0.12065 0.2794)
			(end -0.12065 0.3048)
			(stroke
				(width 0.1)
				(type default)
			)
			(layer "F.Fab")
		)
		(fp_line
			(start -0.12065 0.3048)
			(end -0.67945 0.3048)
			(stroke
				(width 0.1)
				(type default)
			)
			(layer "F.Fab")
		)
		(fp_line
			(start 0.120396 0.2794)
			(end -0.12065 0.2794)
			(stroke
				(width 0.1)
				(type default)
			)
			(layer "F.Fab")
		)
		(fp_line
			(start 0.120396 0.3048)
			(end 0.120396 0.2794)
			(stroke
				(width 0.1)
				(type default)
			)
			(layer "F.Fab")
		)
		(fp_line
			(start 0.12065 -0.3048)
			(end 0.67945 -0.3048)
			(stroke
				(width 0.1)
				(type default)
			)
			(layer "F.Fab")
		)
		(fp_line
			(start 0.12065 -0.2794)
			(end 0.12065 -0.3048)
			(stroke
				(width 0.1)
				(type default)
			)
			(layer "F.Fab")
		)
		(fp_line
			(start 0.67945 -0.3048)
			(end 0.67945 0.3048)
			(stroke
				(width 0.1)
				(type default)
			)
			(layer "F.Fab")
		)
		(fp_line
			(start 0.67945 0.3048)
			(end 0.120396 0.3048)
			(stroke
				(width 0.1)
				(type default)
			)
			(layer "F.Fab")
		)
		(pad "1" smd rect
			(at -0.40005 0 180)
			(size 0.4572 0.508)
			(layers "F.Cu" "F.Mask" "F.Paste")
			(net "FAN_1_OK_LED_R_N")
		)
		(pad "2" smd rect
			(at 0.40005 0 180)
			(size 0.4572 0.508)
			(layers "F.Cu" "F.Mask" "F.Paste")
			(net "FAN_1_OK_R_LED_N")
		)
	)
	(footprint ""
		(layer "F.Cu")
		(at 29.21 -104.648 -90)
		(property "Reference" "U400"
			(at -2.667 -1.16967 90)
			(unlocked yes)
			(layer "F.SilkS")
			(effects
				(font
					(size 0.7874 0.5842)
					(thickness 0.1524)
				)
				(justify left)
			)
		)
		(property "Value" ""
			(at 0 0 270)
			(layer "F.Fab")
			(effects
				(font
					(size 1.27 1.27)
				)
			)
		)
		(duplicate_pad_numbers_are_jumpers no)
		(fp_line
			(start -1.33096 1.100074)
			(end -1.33096 -1.100074)
			(stroke
				(width 0.1524)
				(type default)
			)
			(layer "F.SilkS")
		)
		(fp_line
			(start 1.33096 1.100074)
			(end -1.33096 1.100074)
			(stroke
				(width 0.1524)
				(type default)
			)
			(layer "F.SilkS")
		)
		(fp_line
			(start 0 -0.649986)
			(end 0.381 -1.100074)
			(stroke
				(width 0.1524)
				(type default)
			)
			(layer "F.SilkS")
		)
		(fp_line
			(start -1.33096 -1.100074)
			(end -0.381 -1.100074)
			(stroke
				(width 0.1524)
				(type default)
			)
			(layer "F.SilkS")
		)
		(fp_line
			(start -0.381 -1.100074)
			(end 0 -0.649986)
			(stroke
				(width 0.1524)
				(type default)
			)
			(layer "F.SilkS")
		)
		(fp_line
			(start 0.381 -1.100074)
			(end 1.33096 -1.100074)
			(stroke
				(width 0.1524)
				(type default)
			)
			(layer "F.SilkS")
		)
		(fp_line
			(start 1.33096 -1.100074)
			(end 1.33096 1.100074)
			(stroke
				(width 0.1524)
				(type default)
			)
			(layer "F.SilkS")
		)
		(fp_poly
			(pts
				(xy -2.209292 -1.029462) (xy -2.209292 -0.521462) (xy -1.447292 -0.775462)
			)
			(stroke
				(width 0)
				(type default)
			)
			(fill yes)
			(layer "F.SilkS")
		)
		(fp_line
			(start -0.674878 1.100074)
			(end -0.674878 -1.100074)
			(stroke
				(width 0.1)
				(type default)
			)
			(layer "F.Fab")
		)
		(fp_line
			(start 0.674878 1.100074)
			(end -0.674878 1.100074)
			(stroke
				(width 0.1)
				(type default)
			)
			(layer "F.Fab")
		)
		(fp_line
			(start -0.674878 -1.100074)
			(end 0.674878 -1.100074)
			(stroke
				(width 0.1)
				(type default)
			)
			(layer "F.Fab")
		)
		(fp_line
			(start 0.674878 -1.100074)
			(end 0.674878 1.100074)
			(stroke
				(width 0.1)
				(type default)
			)
			(layer "F.Fab")
		)
		(fp_poly
			(pts
				(xy -2.209292 -0.902462) (xy -2.209292 -0.394462) (xy -1.447292 -0.648462)
			)
			(stroke
				(width 0)
				(type default)
			)
			(fill yes)
			(layer "F.Fab")
		)
		(pad "1" smd rect
			(at -0.94996 -0.649986)
			(size 0.4064 0.508)
			(layers "F.Cu" "F.Mask" "F.Paste")
			(net "NC_U400_P1")
		)
		(pad "2" smd rect
			(at -0.94996 0)
			(size 0.4064 0.508)
			(layers "F.Cu" "F.Mask" "F.Paste")
			(net "FAN_5_PWM")
		)
		(pad "3" smd rect
			(at -0.94996 0.649986)
			(size 0.4064 0.508)
			(layers "F.Cu" "F.Mask" "F.Paste")
			(net "GND")
		)
		(pad "4" smd rect
			(at 0.94996 0.649986)
			(size 0.4064 0.508)
			(layers "F.Cu" "F.Mask" "F.Paste")
			(net "FAN_5_PWM_BUF")
		)
		(pad "5" smd rect
			(at 0.94996 -0.649986)
			(size 0.4064 0.508)
			(layers "F.Cu" "F.Mask" "F.Paste")
			(net "P3V3_AUX")
		)
	)
	(footprint ""
		(layer "F.Cu")
		(at 2.794 -189.992)
		(property "Reference" "R317"
			(at 0 0 0)
			(layer "F.SilkS")
			(hide yes)
			(effects
				(font
					(size 1.27 1.27)
				)
			)
		)
		(property "Value" ""
			(at 0 0 0)
			(layer "F.Fab")
			(effects
				(font
					(size 1.27 1.27)
				)
			)
		)
		(duplicate_pad_numbers_are_jumpers no)
		(fp_line
			(start -0.7874 -0.4064)
			(end 0.7874 -0.4064)
			(stroke
				(width 0.1524)
				(type default)
			)
			(layer "F.SilkS")
		)
		(fp_line
			(start -0.7874 0.4064)
			(end -0.7874 -0.4064)
			(stroke
				(width 0.1524)
				(type default)
			)
			(layer "F.SilkS")
		)
		(fp_line
			(start 0.7874 -0.4064)
			(end 0.7874 0.4064)
			(stroke
				(width 0.1524)
				(type default)
			)
			(layer "F.SilkS")
		)
		(fp_line
			(start 0.7874 0.4064)
			(end -0.7874 0.4064)
			(stroke
				(width 0.1524)
				(type default)
			)
			(layer "F.SilkS")
		)
		(fp_line
			(start -0.67945 -0.305054)
			(end -0.12065 -0.305054)
			(stroke
				(width 0.1)
				(type default)
			)
			(layer "F.Fab")
		)
		(fp_line
			(start -0.67945 0.3048)
			(end -0.67945 -0.305054)
			(stroke
				(width 0.1)
				(type default)
			)
			(layer "F.Fab")
		)
		(fp_line
			(start -0.12065 -0.305054)
			(end -0.12065 -0.2794)
			(stroke
				(width 0.1)
				(type default)
			)
			(layer "F.Fab")
		)
		(fp_line
			(start -0.12065 -0.2794)
			(end 0.12065 -0.2794)
			(stroke
				(width 0.1)
				(type default)
			)
			(layer "F.Fab")
		)
		(fp_line
			(start -0.12065 0.2794)
			(end -0.12065 0.3048)
			(stroke
				(width 0.1)
				(type default)
			)
			(layer "F.Fab")
		)
		(fp_line
			(start -0.12065 0.3048)
			(end -0.67945 0.3048)
			(stroke
				(width 0.1)
				(type default)
			)
			(layer "F.Fab")
		)
		(fp_line
			(start 0.120396 0.2794)
			(end -0.12065 0.2794)
			(stroke
				(width 0.1)
				(type default)
			)
			(layer "F.Fab")
		)
		(fp_line
			(start 0.120396 0.3048)
			(end 0.120396 0.2794)
			(stroke
				(width 0.1)
				(type default)
			)
			(layer "F.Fab")
		)
		(fp_line
			(start 0.12065 -0.3048)
			(end 0.67945 -0.3048)
			(stroke
				(width 0.1)
				(type default)
			)
			(layer "F.Fab")
		)
		(fp_line
			(start 0.12065 -0.2794)
			(end 0.12065 -0.3048)
			(stroke
				(width 0.1)
				(type default)
			)
			(layer "F.Fab")
		)
		(fp_line
			(start 0.67945 -0.3048)
			(end 0.67945 0.3048)
			(stroke
				(width 0.1)
				(type default)
			)
			(layer "F.Fab")
		)
		(fp_line
			(start 0.67945 0.3048)
			(end 0.120396 0.3048)
			(stroke
				(width 0.1)
				(type default)
			)
			(layer "F.Fab")
		)
		(pad "1" smd circle
			(at -0.40005 0)
			(size 0 0)
			(layers "F.Cu" "F.Mask" "F.Paste")
			(net "GND")
		)
		(pad "2" smd circle
			(at 0.40005 0)
			(size 0 0)
			(layers "F.Cu" "F.Mask" "F.Paste")
			(net "FRU_ADDR0")
		)
	)
	(footprint ""
		(layer "F.Cu")
		(at 34.417 -295.148)
		(property "Reference" "U369"
			(at -5.588 -1.49733 0)
			(unlocked yes)
			(layer "F.SilkS")
			(effects
				(font
					(size 0.7874 0.5842)
					(thickness 0.1524)
				)
				(justify left)
			)
		)
		(property "Value" ""
			(at 0 0 0)
			(layer "F.Fab")
			(effects
				(font
					(size 1.27 1.27)
				)
			)
		)
		(duplicate_pad_numbers_are_jumpers no)
		(fp_line
			(start -1.335278 -1.100074)
			(end -1.335278 1.100074)
			(stroke
				(width 0.1524)
				(type default)
			)
			(layer "F.SilkS")
		)
		(fp_line
			(start -1.335278 1.100074)
			(end 1.335278 1.100074)
			(stroke
				(width 0.1524)
				(type default)
			)
			(layer "F.SilkS")
		)
		(fp_line
			(start 1.335278 -1.100074)
			(end -1.335278 -1.100074)
			(stroke
				(width 0.1524)
				(type default)
			)
			(layer "F.SilkS")
		)
		(fp_line
			(start 1.335278 1.100074)
			(end 1.335278 -1.100074)
			(stroke
				(width 0.1524)
				(type default)
			)
			(layer "F.SilkS")
		)
		(fp_line
			(start -0.674878 -1.100074)
			(end -0.674878 1.100074)
			(stroke
				(width 0.1)
				(type default)
			)
			(layer "F.Fab")
		)
		(fp_line
			(start -0.674878 1.100074)
			(end 0.674878 1.100074)
			(stroke
				(width 0.1)
				(type default)
			)
			(layer "F.Fab")
		)
		(fp_line
			(start 0.674878 -1.100074)
			(end -0.674878 -1.100074)
			(stroke
				(width 0.1)
				(type default)
			)
			(layer "F.Fab")
		)
		(fp_line
			(start 0.674878 1.100074)
			(end 0.674878 -1.100074)
			(stroke
				(width 0.1)
				(type default)
			)
			(layer "F.Fab")
		)
		(pad "D" smd rect
			(at 0.8001 0 270)
			(size 0.6096 0.8128)
			(layers "F.Cu" "F.Mask" "F.Paste")
			(net "FAN_0_FAIL_LED_R_N")
		)
		(pad "G" smd rect
			(at -0.8001 -0.649986 270)
			(size 0.6096 0.8128)
			(layers "F.Cu" "F.Mask" "F.Paste")
			(net "FAN_0_FAIL_R_LED")
		)
		(pad "S" smd rect
			(at -0.8001 0.649986 270)
			(size 0.6096 0.8128)
			(layers "F.Cu" "F.Mask" "F.Paste")
			(net "GND")
		)
	)
	(footprint ""
		(layer "F.Cu")
		(at 25.527 -126.619 180)
		(property "Reference" "R4954"
			(at 0 0 180)
			(layer "F.SilkS")
			(hide yes)
			(effects
				(font
					(size 1.27 1.27)
				)
			)
		)
		(property "Value" ""
			(at 0 0 180)
			(layer "F.Fab")
			(effects
				(font
					(size 1.27 1.27)
				)
			)
		)
		(duplicate_pad_numbers_are_jumpers no)
		(fp_line
			(start 0.7874 0.4064)
			(end -0.7874 0.4064)
			(stroke
				(width 0.1524)
				(type default)
			)
			(layer "F.SilkS")
		)
		(fp_line
			(start 0.7874 -0.4064)
			(end 0.7874 0.4064)
			(stroke
				(width 0.1524)
				(type default)
			)
			(layer "F.SilkS")
		)
		(fp_line
			(start -0.7874 0.4064)
			(end -0.7874 -0.4064)
			(stroke
				(width 0.1524)
				(type default)
			)
			(layer "F.SilkS")
		)
		(fp_line
			(start -0.7874 -0.4064)
			(end 0.7874 -0.4064)
			(stroke
				(width 0.1524)
				(type default)
			)
			(layer "F.SilkS")
		)
		(fp_line
			(start 0.67945 0.3048)
			(end 0.120396 0.3048)
			(stroke
				(width 0.1)
				(type default)
			)
			(layer "F.Fab")
		)
		(fp_line
			(start 0.67945 -0.3048)
			(end 0.67945 0.3048)
			(stroke
				(width 0.1)
				(type default)
			)
			(layer "F.Fab")
		)
		(fp_line
			(start 0.12065 -0.2794)
			(end 0.12065 -0.3048)
			(stroke
				(width 0.1)
				(type default)
			)
			(layer "F.Fab")
		)
		(fp_line
			(start 0.12065 -0.3048)
			(end 0.67945 -0.3048)
			(stroke
				(width 0.1)
				(type default)
			)
			(layer "F.Fab")
		)
		(fp_line
			(start 0.120396 0.3048)
			(end 0.120396 0.2794)
			(stroke
				(width 0.1)
				(type default)
			)
			(layer "F.Fab")
		)
		(fp_line
			(start 0.120396 0.2794)
			(end -0.12065 0.2794)
			(stroke
				(width 0.1)
				(type default)
			)
			(layer "F.Fab")
		)
		(fp_line
			(start -0.12065 0.3048)
			(end -0.67945 0.3048)
			(stroke
				(width 0.1)
				(type default)
			)
			(layer "F.Fab")
		)
		(fp_line
			(start -0.12065 0.2794)
			(end -0.12065 0.3048)
			(stroke
				(width 0.1)
				(type default)
			)
			(layer "F.Fab")
		)
		(fp_line
			(start -0.12065 -0.2794)
			(end 0.12065 -0.2794)
			(stroke
				(width 0.1)
				(type default)
			)
			(layer "F.Fab")
		)
		(fp_line
			(start -0.12065 -0.305054)
			(end -0.12065 -0.2794)
			(stroke
				(width 0.1)
				(type default)
			)
			(layer "F.Fab")
		)
		(fp_line
			(start -0.67945 0.3048)
			(end -0.67945 -0.305054)
			(stroke
				(width 0.1)
				(type default)
			)
			(layer "F.Fab")
		)
		(fp_line
			(start -0.67945 -0.305054)
			(end -0.12065 -0.305054)
			(stroke
				(width 0.1)
				(type default)
			)
			(layer "F.Fab")
		)
		(pad "1" smd circle
			(at -0.40005 0 180)
			(size 0 0)
			(layers "F.Cu" "F.Mask" "F.Paste")
			(net "GND")
		)
		(pad "2" smd circle
			(at 0.40005 0 180)
			(size 0 0)
			(layers "F.Cu" "F.Mask" "F.Paste")
			(net "MAX31790_U330_PWM_START1")
		)
	)
	(footprint ""
		(layer "F.Cu")
		(at 18.679922 -290.2331)
		(property "Reference" "C2058"
			(at 0 0 0)
			(layer "F.SilkS")
			(hide yes)
			(effects
				(font
					(size 1.27 1.27)
				)
			)
		)
		(property "Value" ""
			(at 0 0 0)
			(layer "F.Fab")
			(effects
				(font
					(size 1.27 1.27)
				)
			)
		)
		(duplicate_pad_numbers_are_jumpers no)
		(fp_line
			(start -0.7874 -0.4064)
			(end 0.7874 -0.4064)
			(stroke
				(width 0.1524)
				(type default)
			)
			(layer "F.SilkS")
		)
		(fp_line
			(start -0.7874 0.4064)
			(end -0.7874 -0.4064)
			(stroke
				(width 0.1524)
				(type default)
			)
			(layer "F.SilkS")
		)
		(fp_line
			(start 0.7874 -0.4064)
			(end 0.7874 0.4064)
			(stroke
				(width 0.1524)
				(type default)
			)
			(layer "F.SilkS")
		)
		(fp_line
			(start 0.7874 0.4064)
			(end -0.7874 0.4064)
			(stroke
				(width 0.1524)
				(type default)
			)
			(layer "F.SilkS")
		)
		(fp_line
			(start -0.67945 -0.305054)
			(end -0.12065 -0.305054)
			(stroke
				(width 0.1)
				(type default)
			)
			(layer "F.Fab")
		)
		(fp_line
			(start -0.67945 0.3048)
			(end -0.67945 -0.305054)
			(stroke
				(width 0.1)
				(type default)
			)
			(layer "F.Fab")
		)
		(fp_line
			(start -0.12065 -0.305054)
			(end -0.12065 -0.2794)
			(stroke
				(width 0.1)
				(type default)
			)
			(layer "F.Fab")
		)
		(fp_line
			(start -0.12065 -0.2794)
			(end 0.12065 -0.2794)
			(stroke
				(width 0.1)
				(type default)
			)
			(layer "F.Fab")
		)
		(fp_line
			(start -0.12065 0.2794)
			(end -0.12065 0.3048)
			(stroke
				(width 0.1)
				(type default)
			)
			(layer "F.Fab")
		)
		(fp_line
			(start -0.12065 0.3048)
			(end -0.67945 0.3048)
			(stroke
				(width 0.1)
				(type default)
			)
			(layer "F.Fab")
		)
		(fp_line
			(start 0.120396 0.2794)
			(end -0.12065 0.2794)
			(stroke
				(width 0.1)
				(type default)
			)
			(layer "F.Fab")
		)
		(fp_line
			(start 0.120396 0.3048)
			(end 0.120396 0.2794)
			(stroke
				(width 0.1)
				(type default)
			)
			(layer "F.Fab")
		)
		(fp_line
			(start 0.12065 -0.3048)
			(end 0.67945 -0.3048)
			(stroke
				(width 0.1)
				(type default)
			)
			(layer "F.Fab")
		)
		(fp_line
			(start 0.12065 -0.2794)
			(end 0.12065 -0.3048)
			(stroke
				(width 0.1)
				(type default)
			)
			(layer "F.Fab")
		)
		(fp_line
			(start 0.67945 -0.3048)
			(end 0.67945 0.3048)
			(stroke
				(width 0.1)
				(type default)
			)
			(layer "F.Fab")
		)
		(fp_line
			(start 0.67945 0.3048)
			(end 0.120396 0.3048)
			(stroke
				(width 0.1)
				(type default)
			)
			(layer "F.Fab")
		)
		(pad "1" smd circle
			(at -0.40005 0)
			(size 0 0)
			(layers "F.Cu" "F.Mask" "F.Paste")
			(net "FAN_7_TACH_IL_R")
		)
		(pad "2" smd circle
			(at 0.40005 0)
			(size 0 0)
			(layers "F.Cu" "F.Mask" "F.Paste")
			(net "GND")
		)
	)
)
